(kicad_pcb
	(version 20260206)
	(generator "pcbnew")
	(generator_version "10.0")
	(general
		(thickness 1.6)
		(legacy_teardrops no)
	)
	(paper "A4")
	(title_block
		(title "03242023_DA0F0TMBIJ0_F0T_Motherboard_J_brd_V01_OCP.brd")
		(comment 1 "Grand Teton / footprint 1508 of 6105 (J20), pads 1-112 of 291")
	)
	(layers
		(0 "F.Cu" signal "TOP")
		(4 "In1.Cu" signal "GND")
		(6 "In2.Cu" signal "IN1")
		(8 "In3.Cu" signal "GND1")
		(10 "In4.Cu" signal "IN2")
		(12 "In5.Cu" signal "GND2")
		(14 "In6.Cu" signal "IN3")
		(16 "In7.Cu" signal "GND3")
		(18 "In8.Cu" signal "VCC")
		(20 "In9.Cu" signal "VCC1")
		(22 "In10.Cu" signal "GND4")
		(24 "In11.Cu" signal "IN4")
		(26 "In12.Cu" signal "GND5")
		(28 "In13.Cu" signal "IN5")
		(30 "In14.Cu" signal "GND6")
		(32 "In15.Cu" signal "IN6")
		(34 "In16.Cu" signal "GND7")
		(2 "B.Cu" signal "BOTTOM")
		(9 "F.Adhes" user "F.Adhesive")
		(11 "B.Adhes" user "B.Adhesive")
		(13 "F.Paste" user "Package Geometry/Pastemask Top")
		(15 "B.Paste" user "Package Geometry/Pastemask Bottom")
		(5 "F.SilkS" user "Ref Des/Silkscreen Top")
		(7 "B.SilkS" user "Ref Des/Silkscreen Bottom")
		(1 "F.Mask" user "Board Geometry/Soldermask Top")
		(3 "B.Mask" user "Board Geometry/Soldermask Bottom")
		(17 "Dwgs.User" user "User.Drawings")
		(19 "Cmts.User" user "User.Comments")
		(21 "Eco1.User" user "User.Eco1")
		(23 "Eco2.User" user "User.Eco2")
		(25 "Edge.Cuts" user "Board Geometry/Outline")
		(27 "Margin" user)
		(31 "F.CrtYd" user "Package Geometry/Place Bound Top")
		(29 "B.CrtYd" user "Package Geometry/Place Bound Bottom")
		(35 "F.Fab" user "Ref Des/Assembly Top")
		(33 "B.Fab" user "Ref Des/Assembly Bottom")
	)
	(footprint ""
		(layer "F.Cu")
		(at 47.90948 -258.091686)
		(property "Reference" "J20"
			(at -2.74066 -81.678272 0)
			(unlocked yes)
			(layer "F.SilkS")
			(effects
				(font
					(size 0.7874 0.5842)
					(thickness 0.1524)
				)
				(justify left)
			)
		)
		(property "Value" ""
			(at 0 0 0)
			(layer "F.Fab")
			(effects
				(font
					(size 1.27 1.27)
				)
			)
		)
		(duplicate_pad_numbers_are_jumpers no)
		(pad "1" smd rect
			(at -2.050034 -63.324994 270)
			(size 0.519938 1.4986)
			(layers "F.Cu" "F.Mask" "F.Paste")
			(net "P12V_S3_AUX_CPU1_NVDIMM")
		)
		(pad "2" smd rect
			(at -2.050034 -62.47511 270)
			(size 0.519938 1.4986)
			(layers "F.Cu" "F.Mask" "F.Paste")
			(net "TP_CHB_CPU1_DIMM2_FRU_0")
		)
		(pad "3" smd rect
			(at -2.050034 -61.624972 270)
			(size 0.519938 1.4986)
			(layers "F.Cu" "F.Mask" "F.Paste")
			(net "P3V3_AUX")
		)
		(pad "4" smd rect
			(at -2.050034 -60.775088 270)
			(size 0.519938 1.4986)
			(layers "F.Cu" "F.Mask" "F.Paste")
			(net "I3C_SPD_DDRABCD_CPU1_LVC1_SCL_3")
		)
		(pad "5" smd rect
			(at -2.050034 -59.92495 270)
			(size 0.519938 1.4986)
			(layers "F.Cu" "F.Mask" "F.Paste")
			(net "I3C_SPD_DDRABCD_CPU1_LVC1_SDA")
		)
		(pad "6" smd rect
			(at -2.050034 -59.075066 270)
			(size 0.519938 1.4986)
			(layers "F.Cu" "F.Mask" "F.Paste")
			(net "GND")
		)
		(pad "7" smd rect
			(at -2.050034 -58.224928 270)
			(size 0.519938 1.4986)
			(layers "F.Cu" "F.Mask" "F.Paste")
			(net "M_B_CPU1_SA_DQ<0>")
		)
		(pad "8" smd rect
			(at -2.050034 -57.375044 270)
			(size 0.519938 1.4986)
			(layers "F.Cu" "F.Mask" "F.Paste")
			(net "GND")
		)
		(pad "9" smd rect
			(at -2.050034 -56.524906 270)
			(size 0.519938 1.4986)
			(layers "F.Cu" "F.Mask" "F.Paste")
			(net "M_B_CPU1_SA_DQ<1>")
		)
		(pad "10" smd rect
			(at -2.050034 -55.675022 270)
			(size 0.519938 1.4986)
			(layers "F.Cu" "F.Mask" "F.Paste")
			(net "GND")
		)
		(pad "11" smd rect
			(at -2.050034 -54.824884 270)
			(size 0.519938 1.4986)
			(layers "F.Cu" "F.Mask" "F.Paste")
			(net "M_B_CPU1_SA_DQS_DP<0>")
		)
		(pad "12" smd rect
			(at -2.050034 -53.975 270)
			(size 0.519938 1.4986)
			(layers "F.Cu" "F.Mask" "F.Paste")
			(net "M_B_CPU1_SA_DQS_DN<0>")
		)
		(pad "13" smd rect
			(at -2.050034 -53.125116 270)
			(size 0.519938 1.4986)
			(layers "F.Cu" "F.Mask" "F.Paste")
			(net "GND")
		)
		(pad "14" smd rect
			(at -2.050034 -52.274978 270)
			(size 0.519938 1.4986)
			(layers "F.Cu" "F.Mask" "F.Paste")
			(net "M_B_CPU1_SA_DQ<4>")
		)
		(pad "15" smd rect
			(at -2.050034 -51.425094 270)
			(size 0.519938 1.4986)
			(layers "F.Cu" "F.Mask" "F.Paste")
			(net "GND")
		)
		(pad "16" smd rect
			(at -2.050034 -50.574956 270)
			(size 0.519938 1.4986)
			(layers "F.Cu" "F.Mask" "F.Paste")
			(net "M_B_CPU1_SA_DQ<5>")
		)
		(pad "17" smd rect
			(at -2.050034 -49.725072 270)
			(size 0.519938 1.4986)
			(layers "F.Cu" "F.Mask" "F.Paste")
			(net "GND")
		)
		(pad "18" smd rect
			(at -2.050034 -48.874934 270)
			(size 0.519938 1.4986)
			(layers "F.Cu" "F.Mask" "F.Paste")
			(net "M_B_CPU1_SA_DQ<8>")
		)
		(pad "19" smd rect
			(at -2.050034 -48.02505 270)
			(size 0.519938 1.4986)
			(layers "F.Cu" "F.Mask" "F.Paste")
			(net "GND")
		)
		(pad "20" smd rect
			(at -2.050034 -47.174912 270)
			(size 0.519938 1.4986)
			(layers "F.Cu" "F.Mask" "F.Paste")
			(net "M_B_CPU1_SA_DQ<9>")
		)
		(pad "21" smd rect
			(at -2.050034 -46.325028 270)
			(size 0.519938 1.4986)
			(layers "F.Cu" "F.Mask" "F.Paste")
			(net "GND")
		)
		(pad "22" smd rect
			(at -2.050034 -45.47489 270)
			(size 0.519938 1.4986)
			(layers "F.Cu" "F.Mask" "F.Paste")
			(net "M_B_CPU1_SA_DQS_DP<1>")
		)
		(pad "23" smd rect
			(at -2.050034 -44.625006 270)
			(size 0.519938 1.4986)
			(layers "F.Cu" "F.Mask" "F.Paste")
			(net "M_B_CPU1_SA_DQS_DN<1>")
		)
		(pad "24" smd rect
			(at -2.050034 -43.775122 270)
			(size 0.519938 1.4986)
			(layers "F.Cu" "F.Mask" "F.Paste")
			(net "GND")
		)
		(pad "25" smd rect
			(at -2.050034 -42.924984 270)
			(size 0.519938 1.4986)
			(layers "F.Cu" "F.Mask" "F.Paste")
			(net "M_B_CPU1_SA_DQ<12>")
		)
		(pad "26" smd rect
			(at -2.050034 -42.0751 270)
			(size 0.519938 1.4986)
			(layers "F.Cu" "F.Mask" "F.Paste")
			(net "GND")
		)
		(pad "27" smd rect
			(at -2.050034 -41.224962 270)
			(size 0.519938 1.4986)
			(layers "F.Cu" "F.Mask" "F.Paste")
			(net "M_B_CPU1_SA_DQ<13>")
		)
		(pad "28" smd rect
			(at -2.050034 -40.375078 270)
			(size 0.519938 1.4986)
			(layers "F.Cu" "F.Mask" "F.Paste")
			(net "GND")
		)
		(pad "29" smd rect
			(at -2.050034 -39.52494 270)
			(size 0.519938 1.4986)
			(layers "F.Cu" "F.Mask" "F.Paste")
			(net "M_B_CPU1_SA_DQ<16>")
		)
		(pad "30" smd rect
			(at -2.050034 -38.675056 270)
			(size 0.519938 1.4986)
			(layers "F.Cu" "F.Mask" "F.Paste")
			(net "GND")
		)
		(pad "31" smd rect
			(at -2.050034 -37.824918 270)
			(size 0.519938 1.4986)
			(layers "F.Cu" "F.Mask" "F.Paste")
			(net "M_B_CPU1_SA_DQ<17>")
		)
		(pad "32" smd rect
			(at -2.050034 -36.975034 270)
			(size 0.519938 1.4986)
			(layers "F.Cu" "F.Mask" "F.Paste")
			(net "GND")
		)
		(pad "33" smd rect
			(at -2.050034 -36.124896 270)
			(size 0.519938 1.4986)
			(layers "F.Cu" "F.Mask" "F.Paste")
			(net "M_B_CPU1_SA_DQS_DP<2>")
		)
		(pad "34" smd rect
			(at -2.050034 -35.275012 270)
			(size 0.519938 1.4986)
			(layers "F.Cu" "F.Mask" "F.Paste")
			(net "M_B_CPU1_SA_DQS_DN<2>")
		)
		(pad "35" smd rect
			(at -2.050034 -34.425128 270)
			(size 0.519938 1.4986)
			(layers "F.Cu" "F.Mask" "F.Paste")
			(net "GND")
		)
		(pad "36" smd rect
			(at -2.050034 -33.57499 270)
			(size 0.519938 1.4986)
			(layers "F.Cu" "F.Mask" "F.Paste")
			(net "M_B_CPU1_SA_DQ<20>")
		)
		(pad "37" smd rect
			(at -2.050034 -32.725106 270)
			(size 0.519938 1.4986)
			(layers "F.Cu" "F.Mask" "F.Paste")
			(net "GND")
		)
		(pad "38" smd rect
			(at -2.050034 -31.874968 270)
			(size 0.519938 1.4986)
			(layers "F.Cu" "F.Mask" "F.Paste")
			(net "M_B_CPU1_SA_DQ<21>")
		)
		(pad "39" smd rect
			(at -2.050034 -31.025084 270)
			(size 0.519938 1.4986)
			(layers "F.Cu" "F.Mask" "F.Paste")
			(net "GND")
		)
		(pad "40" smd rect
			(at -2.050034 -30.174946 270)
			(size 0.519938 1.4986)
			(layers "F.Cu" "F.Mask" "F.Paste")
			(net "M_B_CPU1_SA_DQ<24>")
		)
		(pad "41" smd rect
			(at -2.050034 -29.325062 270)
			(size 0.519938 1.4986)
			(layers "F.Cu" "F.Mask" "F.Paste")
			(net "GND")
		)
		(pad "42" smd rect
			(at -2.050034 -28.474924 270)
			(size 0.519938 1.4986)
			(layers "F.Cu" "F.Mask" "F.Paste")
			(net "M_B_CPU1_SA_DQ<25>")
		)
		(pad "43" smd rect
			(at -2.050034 -27.62504 270)
			(size 0.519938 1.4986)
			(layers "F.Cu" "F.Mask" "F.Paste")
			(net "GND")
		)
		(pad "44" smd rect
			(at -2.050034 -26.774902 270)
			(size 0.519938 1.4986)
			(layers "F.Cu" "F.Mask" "F.Paste")
			(net "M_B_CPU1_SA_DQS_DP<3>")
		)
		(pad "45" smd rect
			(at -2.050034 -25.925018 270)
			(size 0.519938 1.4986)
			(layers "F.Cu" "F.Mask" "F.Paste")
			(net "M_B_CPU1_SA_DQS_DN<3>")
		)
		(pad "46" smd rect
			(at -2.050034 -25.07488 270)
			(size 0.519938 1.4986)
			(layers "F.Cu" "F.Mask" "F.Paste")
			(net "GND")
		)
		(pad "47" smd rect
			(at -2.050034 -24.224996 270)
			(size 0.519938 1.4986)
			(layers "F.Cu" "F.Mask" "F.Paste")
			(net "M_B_CPU1_SA_DQ<28>")
		)
		(pad "48" smd rect
			(at -2.050034 -23.375112 270)
			(size 0.519938 1.4986)
			(layers "F.Cu" "F.Mask" "F.Paste")
			(net "GND")
		)
		(pad "49" smd rect
			(at -2.050034 -22.524974 270)
			(size 0.519938 1.4986)
			(layers "F.Cu" "F.Mask" "F.Paste")
			(net "M_B_CPU1_SA_DQ<29>")
		)
		(pad "50" smd rect
			(at -2.050034 -21.67509 270)
			(size 0.519938 1.4986)
			(layers "F.Cu" "F.Mask" "F.Paste")
			(net "GND")
		)
		(pad "51" smd rect
			(at -2.050034 -20.824952 270)
			(size 0.519938 1.4986)
			(layers "F.Cu" "F.Mask" "F.Paste")
			(net "M_B_CPU1_SA_CB<0>")
		)
		(pad "52" smd rect
			(at -2.050034 -19.975068 270)
			(size 0.519938 1.4986)
			(layers "F.Cu" "F.Mask" "F.Paste")
			(net "GND")
		)
		(pad "53" smd rect
			(at -2.050034 -19.12493 270)
			(size 0.519938 1.4986)
			(layers "F.Cu" "F.Mask" "F.Paste")
			(net "M_B_CPU1_SA_CB<1>")
		)
		(pad "54" smd rect
			(at -2.050034 -18.275046 270)
			(size 0.519938 1.4986)
			(layers "F.Cu" "F.Mask" "F.Paste")
			(net "GND")
		)
		(pad "55" smd rect
			(at -2.050034 -17.424908 270)
			(size 0.519938 1.4986)
			(layers "F.Cu" "F.Mask" "F.Paste")
			(net "M_B_CPU1_SA_DQS_DP<4>")
		)
		(pad "56" smd rect
			(at -2.050034 -16.575024 270)
			(size 0.519938 1.4986)
			(layers "F.Cu" "F.Mask" "F.Paste")
			(net "M_B_CPU1_SA_DQS_DN<4>")
		)
		(pad "57" smd rect
			(at -2.050034 -15.724886 270)
			(size 0.519938 1.4986)
			(layers "F.Cu" "F.Mask" "F.Paste")
			(net "GND")
		)
		(pad "58" smd rect
			(at -2.050034 -14.875002 270)
			(size 0.519938 1.4986)
			(layers "F.Cu" "F.Mask" "F.Paste")
			(net "M_B_CPU1_SA_CB<4>")
		)
		(pad "59" smd rect
			(at -2.050034 -14.025118 270)
			(size 0.519938 1.4986)
			(layers "F.Cu" "F.Mask" "F.Paste")
			(net "GND")
		)
		(pad "60" smd rect
			(at -2.050034 -13.17498 270)
			(size 0.519938 1.4986)
			(layers "F.Cu" "F.Mask" "F.Paste")
			(net "M_B_CPU1_SA_CB<5>")
		)
		(pad "61" smd rect
			(at -2.050034 -12.325096 270)
			(size 0.519938 1.4986)
			(layers "F.Cu" "F.Mask" "F.Paste")
			(net "GND")
		)
		(pad "62" smd rect
			(at -2.050034 -11.474958 270)
			(size 0.519938 1.4986)
			(layers "F.Cu" "F.Mask" "F.Paste")
			(net "M_B_CPU1_ALERT_N")
		)
		(pad "63" smd rect
			(at -2.050034 -10.625074 270)
			(size 0.519938 1.4986)
			(layers "F.Cu" "F.Mask" "F.Paste")
			(net "GND")
		)
		(pad "64" smd rect
			(at -2.050034 -9.774936 270)
			(size 0.519938 1.4986)
			(layers "F.Cu" "F.Mask" "F.Paste")
			(net "M_B_CPU1_SA_CS_N<2>")
		)
		(pad "65" smd rect
			(at -2.050034 -8.925052 270)
			(size 0.519938 1.4986)
			(layers "F.Cu" "F.Mask" "F.Paste")
			(net "GND")
		)
		(pad "66" smd rect
			(at -2.050034 -8.074914 270)
			(size 0.519938 1.4986)
			(layers "F.Cu" "F.Mask" "F.Paste")
			(net "M_B_CPU1_SA_CA<0>")
		)
		(pad "67" smd rect
			(at -2.050034 -7.22503 270)
			(size 0.519938 1.4986)
			(layers "F.Cu" "F.Mask" "F.Paste")
			(net "GND")
		)
		(pad "68" smd rect
			(at -2.050034 -6.374892 270)
			(size 0.519938 1.4986)
			(layers "F.Cu" "F.Mask" "F.Paste")
			(net "M_B_CPU1_SA_CA<2>")
		)
		(pad "69" smd rect
			(at -2.050034 -5.525008 270)
			(size 0.519938 1.4986)
			(layers "F.Cu" "F.Mask" "F.Paste")
			(net "GND")
		)
		(pad "70" smd rect
			(at -2.050034 -4.675124 270)
			(size 0.519938 1.4986)
			(layers "F.Cu" "F.Mask" "F.Paste")
			(net "M_B_CPU1_SA_CA<4>")
		)
		(pad "71" smd rect
			(at -2.050034 -3.824986 270)
			(size 0.519938 1.4986)
			(layers "F.Cu" "F.Mask" "F.Paste")
			(net "GND")
		)
		(pad "72" smd rect
			(at -2.050034 -2.975102 270)
			(size 0.519938 1.4986)
			(layers "F.Cu" "F.Mask" "F.Paste")
			(net "M_B_CPU1_SA_CA<6>")
		)
		(pad "73" smd rect
			(at -2.050034 -2.124964 270)
			(size 0.519938 1.4986)
			(layers "F.Cu" "F.Mask" "F.Paste")
			(net "GND")
		)
		(pad "74" smd rect
			(at -2.050034 -1.27508 270)
			(size 0.519938 1.4986)
			(layers "F.Cu" "F.Mask" "F.Paste")
			(net "M_B_CPU1_SA_PAR")
		)
		(pad "75" smd rect
			(at -2.050034 -0.424942 270)
			(size 0.519938 1.4986)
			(layers "F.Cu" "F.Mask" "F.Paste")
			(net "GND")
		)
		(pad "76" smd rect
			(at -2.050034 5.525008 270)
			(size 0.519938 1.4986)
			(layers "F.Cu" "F.Mask" "F.Paste")
			(net "M_B_CPU1_SB_CA<0>")
		)
		(pad "77" smd rect
			(at -2.050034 6.374892 270)
			(size 0.519938 1.4986)
			(layers "F.Cu" "F.Mask" "F.Paste")
			(net "GND")
		)
		(pad "78" smd rect
			(at -2.050034 7.22503 270)
			(size 0.519938 1.4986)
			(layers "F.Cu" "F.Mask" "F.Paste")
			(net "M_B_CPU1_SB_CA<2>")
		)
		(pad "79" smd rect
			(at -2.050034 8.074914 270)
			(size 0.519938 1.4986)
			(layers "F.Cu" "F.Mask" "F.Paste")
			(net "GND")
		)
		(pad "80" smd rect
			(at -2.050034 8.925052 270)
			(size 0.519938 1.4986)
			(layers "F.Cu" "F.Mask" "F.Paste")
			(net "M_B_CPU1_SB_CA<4>")
		)
		(pad "81" smd rect
			(at -2.050034 9.774936 270)
			(size 0.519938 1.4986)
			(layers "F.Cu" "F.Mask" "F.Paste")
			(net "GND")
		)
		(pad "82" smd rect
			(at -2.050034 10.625074 270)
			(size 0.519938 1.4986)
			(layers "F.Cu" "F.Mask" "F.Paste")
			(net "M_B_CPU1_SB_CA<6>")
		)
		(pad "83" smd rect
			(at -2.050034 11.474958 270)
			(size 0.519938 1.4986)
			(layers "F.Cu" "F.Mask" "F.Paste")
			(net "GND")
		)
		(pad "84" smd rect
			(at -2.050034 12.325096 270)
			(size 0.519938 1.4986)
			(layers "F.Cu" "F.Mask" "F.Paste")
			(net "M_B_CPU1_SB_CS_N<2>")
		)
		(pad "85" smd rect
			(at -2.050034 13.17498 270)
			(size 0.519938 1.4986)
			(layers "F.Cu" "F.Mask" "F.Paste")
			(net "GND")
		)
		(pad "86" smd rect
			(at -2.050034 14.025118 270)
			(size 0.519938 1.4986)
			(layers "F.Cu" "F.Mask" "F.Paste")
			(net "M_B_CPU1_SA_RSP<1>")
		)
		(pad "87" smd rect
			(at -2.050034 14.875002 270)
			(size 0.519938 1.4986)
			(layers "F.Cu" "F.Mask" "F.Paste")
			(net "M_B_CPU1_SB_RSP<1>")
		)
		(pad "88" smd rect
			(at -2.050034 15.724886 270)
			(size 0.519938 1.4986)
			(layers "F.Cu" "F.Mask" "F.Paste")
			(net "GND")
		)
		(pad "89" smd rect
			(at -2.050034 16.575024 270)
			(size 0.519938 1.4986)
			(layers "F.Cu" "F.Mask" "F.Paste")
			(net "M_B_CPU1_SB_CB<4>")
		)
		(pad "90" smd rect
			(at -2.050034 17.424908 270)
			(size 0.519938 1.4986)
			(layers "F.Cu" "F.Mask" "F.Paste")
			(net "GND")
		)
		(pad "91" smd rect
			(at -2.050034 18.275046 270)
			(size 0.519938 1.4986)
			(layers "F.Cu" "F.Mask" "F.Paste")
			(net "M_B_CPU1_SB_CB<5>")
		)
		(pad "92" smd rect
			(at -2.050034 19.12493 270)
			(size 0.519938 1.4986)
			(layers "F.Cu" "F.Mask" "F.Paste")
			(net "GND")
		)
		(pad "93" smd rect
			(at -2.050034 19.975068 270)
			(size 0.519938 1.4986)
			(layers "F.Cu" "F.Mask" "F.Paste")
			(net "M_B_CPU1_SB_DQS_DP<9>")
		)
		(pad "94" smd rect
			(at -2.050034 20.824952 270)
			(size 0.519938 1.4986)
			(layers "F.Cu" "F.Mask" "F.Paste")
			(net "M_B_CPU1_SB_DQS_DN<9>")
		)
		(pad "95" smd rect
			(at -2.050034 21.67509 270)
			(size 0.519938 1.4986)
			(layers "F.Cu" "F.Mask" "F.Paste")
			(net "GND")
		)
		(pad "96" smd rect
			(at -2.050034 22.524974 270)
			(size 0.519938 1.4986)
			(layers "F.Cu" "F.Mask" "F.Paste")
			(net "M_B_CPU1_SB_CB<0>")
		)
		(pad "97" smd rect
			(at -2.050034 23.375112 270)
			(size 0.519938 1.4986)
			(layers "F.Cu" "F.Mask" "F.Paste")
			(net "GND")
		)
		(pad "98" smd rect
			(at -2.050034 24.224996 270)
			(size 0.519938 1.4986)
			(layers "F.Cu" "F.Mask" "F.Paste")
			(net "M_B_CPU1_SB_CB<1>")
		)
		(pad "99" smd rect
			(at -2.050034 25.07488 270)
			(size 0.519938 1.4986)
			(layers "F.Cu" "F.Mask" "F.Paste")
			(net "GND")
		)
		(pad "100" smd rect
			(at -2.050034 25.925018 270)
			(size 0.519938 1.4986)
			(layers "F.Cu" "F.Mask" "F.Paste")
			(net "M_B_CPU1_SB_DQ<0>")
		)
		(pad "101" smd rect
			(at -2.050034 26.774902 270)
			(size 0.519938 1.4986)
			(layers "F.Cu" "F.Mask" "F.Paste")
			(net "GND")
		)
		(pad "102" smd rect
			(at -2.050034 27.62504 270)
			(size 0.519938 1.4986)
			(layers "F.Cu" "F.Mask" "F.Paste")
			(net "M_B_CPU1_SB_DQ<1>")
		)
		(pad "103" smd rect
			(at -2.050034 28.474924 270)
			(size 0.519938 1.4986)
			(layers "F.Cu" "F.Mask" "F.Paste")
			(net "GND")
		)
		(pad "104" smd rect
			(at -2.050034 29.325062 270)
			(size 0.519938 1.4986)
			(layers "F.Cu" "F.Mask" "F.Paste")
			(net "M_B_CPU1_SB_DQS_DP<0>")
		)
		(pad "105" smd rect
			(at -2.050034 30.174946 270)
			(size 0.519938 1.4986)
			(layers "F.Cu" "F.Mask" "F.Paste")
			(net "M_B_CPU1_SB_DQS_DN<0>")
		)
		(pad "106" smd rect
			(at -2.050034 31.025084 270)
			(size 0.519938 1.4986)
			(layers "F.Cu" "F.Mask" "F.Paste")
			(net "GND")
		)
		(pad "107" smd rect
			(at -2.050034 31.874968 270)
			(size 0.519938 1.4986)
			(layers "F.Cu" "F.Mask" "F.Paste")
			(net "M_B_CPU1_SB_DQ<4>")
		)
		(pad "108" smd rect
			(at -2.050034 32.725106 270)
			(size 0.519938 1.4986)
			(layers "F.Cu" "F.Mask" "F.Paste")
			(net "GND")
		)
		(pad "109" smd rect
			(at -2.050034 33.57499 270)
			(size 0.519938 1.4986)
			(layers "F.Cu" "F.Mask" "F.Paste")
			(net "M_B_CPU1_SB_DQ<5>")
		)
		(pad "110" smd rect
			(at -2.050034 34.425128 270)
			(size 0.519938 1.4986)
			(layers "F.Cu" "F.Mask" "F.Paste")
			(net "GND")
		)
		(pad "111" smd rect
			(at -2.050034 35.275012 270)
			(size 0.519938 1.4986)
			(layers "F.Cu" "F.Mask" "F.Paste")
			(net "M_B_CPU1_SB_DQ<8>")
		)
		(pad "112" smd rect
			(at -2.050034 36.124896 270)
			(size 0.519938 1.4986)
			(layers "F.Cu" "F.Mask" "F.Paste")
			(net "GND")
		)
	)
)
